FILE_TYPE=LIBRARY_PARTS;
primitive 'CONN12_C73564003','CONN12_C73564003_THMT';
  pin
    'IO1':
      PIN_NUMBER='(1)';
      BIDIRECTIONAL='TRUE';
      INPUT_LOAD='(-0.01,0.01)';
      OUTPUT_LOAD='(1.0,-1.0)';
    'IO10':
      PIN_NUMBER='(10)';
      BIDIRECTIONAL='TRUE';
      INPUT_LOAD='(-0.01,0.01)';
      OUTPUT_LOAD='(1.0,-1.0)';
    'IO11':
      PIN_NUMBER='(11)';
      BIDIRECTIONAL='TRUE';
      INPUT_LOAD='(-0.01,0.01)';
      OUTPUT_LOAD='(1.0,-1.0)';
    'IO12':
      PIN_NUMBER='(12)';
      BIDIRECTIONAL='TRUE';
      INPUT_LOAD='(-0.01,0.01)';
      OUTPUT_LOAD='(1.0,-1.0)';
    'IO2':
      PIN_NUMBER='(2)';
      BIDIRECTIONAL='TRUE';
      INPUT_LOAD='(-0.01,0.01)';
      OUTPUT_LOAD='(1.0,-1.0)';
    'IO3':
      PIN_NUMBER='(3)';
      BIDIRECTIONAL='TRUE';
      INPUT_LOAD='(-0.01,0.01)';
      OUTPUT_LOAD='(1.0,-1.0)';
    'IO4':
      PIN_NUMBER='(4)';
      BIDIRECTIONAL='TRUE';
      INPUT_LOAD='(-0.01,0.01)';
      OUTPUT_LOAD='(1.0,-1.0)';
    'IO5':
      PIN_NUMBER='(5)';
      BIDIRECTIONAL='TRUE';
      INPUT_LOAD='(-0.01,0.01)';
      OUTPUT_LOAD='(1.0,-1.0)';
    'IO6':
      PIN_NUMBER='(6)';
      BIDIRECTIONAL='TRUE';
      INPUT_LOAD='(-0.01,0.01)';
      OUTPUT_LOAD='(1.0,-1.0)';
    'IO7':
      PIN_NUMBER='(7)';
      BIDIRECTIONAL='TRUE';
      INPUT_LOAD='(-0.01,0.01)';
      OUTPUT_LOAD='(1.0,-1.0)';
    'IO8':
      PIN_NUMBER='(8)';
      BIDIRECTIONAL='TRUE';
      INPUT_LOAD='(-0.01,0.01)';
      OUTPUT_LOAD='(1.0,-1.0)';
    'IO9':
      PIN_NUMBER='(9)';
      BIDIRECTIONAL='TRUE';
      INPUT_LOAD='(-0.01,0.01)';
      OUTPUT_LOAD='(1.0,-1.0)';
  end_pin;
  body
    PART_NAME='CONN12_C73564003';
    PHYS_DES_PREFIX='J';
  end_body;
end_primitive;

END.
